# TIMECARD (Time Appliance Project (Time Card)) — schematic netlist excerpt (pin names and nets, part order shuffled) for the footprints in the layout excerpt that follows; sources: Cadence DE-HDL packaged netlist, KiCad conversion of R4006-B0001-02_R01.brd

C97  CAPACITOR  0.1UF 25V 10%  pkg SMC_0402R_H022  page 24 : \1\ = XP3R3V_FPGA ; \2\ = SG

(kicad_pcb
	(version 20260206)
	(generator "pcbnew")
	(generator_version "10.0")
	(general
		(thickness 1.6)
		(legacy_teardrops no)
	)
	(paper "A4")
	(title_block
		(title "timecard-production-celestica-r4006 — R4006-B0001-02_R01.brd")
		(comment 1 "Time Appliance Project (Time Card) / footprints 653-653 of 1113")
	)
	(layers
		(0 "F.Cu" signal "TOP")
		(4 "In1.Cu" signal "L02_GND1")
		(6 "In2.Cu" signal "L03_SIG1")
		(8 "In3.Cu" signal "L04_GND2")
		(10 "In4.Cu" signal "L05_VCC1")
		(12 "In5.Cu" signal "L06_VCC2")
		(14 "In6.Cu" signal "L07_GND3")
		(16 "In7.Cu" signal "L08_SIG2")
		(18 "In8.Cu" signal "L09_GND4")
		(2 "B.Cu" signal "BOTTOM")
		(9 "F.Adhes" user "F.Adhesive")
		(11 "B.Adhes" user "B.Adhesive")
		(13 "F.Paste" user "Package Geometry/Pastemask Top")
		(15 "B.Paste" user "Package Geometry/Pastemask Bottom")
		(5 "F.SilkS" user "Ref Des/Silkscreen Top")
		(7 "B.SilkS" user "Ref Des/Silkscreen Bottom")
		(1 "F.Mask" user "Board Geometry/Soldermask Top")
		(3 "B.Mask" user "Board Geometry/Soldermask Bottom")
		(17 "Dwgs.User" user "User.Drawings")
		(19 "Cmts.User" user "User.Comments")
		(21 "Eco1.User" user "User.Eco1")
		(23 "Eco2.User" user "User.Eco2")
		(25 "Edge.Cuts" user "Board Geometry/Outline")
		(27 "Margin" user)
		(31 "F.CrtYd" user "Package Geometry/Place Bound Top")
		(29 "B.CrtYd" user "Package Geometry/Place Bound Bottom")
		(35 "F.Fab" user "Ref Des/Assembly Top")
		(33 "B.Fab" user "Ref Des/Assembly Bottom")
	)
	(footprint ""
		(layer "F.Cu")
		(at 115.062 -83.058)
		(property "Reference" "C97"
			(at 1.016 -1.10363 0)
			(unlocked yes)
			(layer "F.SilkS")
			(effects
				(font
					(size 0.7874 0.5842)
					(thickness 0.1524)
				)
			)
		)
		(property "Value" "VAL*"
			(at 0.0762 2.067306 0)
			(unlocked yes)
			(layer "F.Fab")
			(hide yes)
			(effects
				(font
					(size 0.7874 0.5842)
					(thickness 0.1524)
				)
			)
		)
		(property "Tolerance" "TOL*"
			(at 0.0762 3.032506 0)
			(unlocked yes)
			(layer "Cmts.User")
			(hide yes)
			(effects
				(font
					(size 0.7874 0.5842)
					(thickness 0.1524)
				)
			)
		)
		(property "User Part Number" "PARTNUM*"
			(at 0.1016 4.023106 0)
			(unlocked yes)
			(layer "Cmts.User")
			(hide yes)
			(effects
				(font
					(size 0.7874 0.5842)
					(thickness 0.1524)
				)
			)
		)
		(property "Device Type" "CAPACITOR-G105-0B104-EK,0.1UF,A"
			(at 0.0508 1.127506 0)
			(unlocked yes)
			(layer "F.Fab")
			(hide yes)
			(effects
				(font
					(size 0.7874 0.5842)
					(thickness 0.1524)
				)
			)
		)
		(duplicate_pad_numbers_are_jumpers no)
		(fp_line
			(start -1.143 -0.5588)
			(end -1.143 0.5588)
			(stroke
				(width 0.1)
				(type default)
			)
			(layer "F.SilkS")
		)
		(fp_line
			(start -1.143 0.5588)
			(end 1.143 0.5588)
			(stroke
				(width 0.1)
				(type default)
			)
			(layer "F.SilkS")
		)
		(fp_line
			(start 1.143 -0.5588)
			(end -1.143 -0.5588)
			(stroke
				(width 0.1)
				(type default)
			)
			(layer "F.SilkS")
		)
		(fp_line
			(start 1.143 0.5588)
			(end 1.143 -0.5588)
			(stroke
				(width 0.1)
				(type default)
			)
			(layer "F.SilkS")
		)
		(fp_poly
			(pts
				(xy -1.143 0.5588) (xy 1.143 0.5588) (xy 1.143 -0.5588) (xy -1.143 -0.5588)
			)
			(stroke
				(width 0)
				(type default)
			)
			(fill no)
			(layer "F.CrtYd")
		)
		(fp_line
			(start -0.508 -0.3048)
			(end -0.508 0.3048)
			(stroke
				(width 0.1)
				(type default)
			)
			(layer "F.Fab")
		)
		(fp_line
			(start -0.508 0.3048)
			(end 0.508 0.3048)
			(stroke
				(width 0.1)
				(type default)
			)
			(layer "F.Fab")
		)
		(fp_line
			(start 0.508 -0.3048)
			(end -0.508 -0.3048)
			(stroke
				(width 0.1)
				(type default)
			)
			(layer "F.Fab")
		)
		(fp_line
			(start 0.508 0.3048)
			(end 0.508 -0.3048)
			(stroke
				(width 0.1)
				(type default)
			)
			(layer "F.Fab")
		)
		(pad "1" smd rect
			(at -0.5334 0)
			(size 0.7112 0.6096)
			(layers "F.Cu" "F.Mask" "F.Paste")
			(net "XP3R3V_FPGA")
		)
		(pad "2" smd rect
			(at 0.5334 0)
			(size 0.7112 0.6096)
			(layers "F.Cu" "F.Mask" "F.Paste")
			(net "SG")
		)
		(zone
			(layer "F.Cu")
			(hatch none 0.5)
			(connect_pads
				(clearance 0)
			)
			(min_thickness 0.25)
			(keepout
				(tracks allowed)
				(vias not_allowed)
				(pads allowed)
				(copperpour not_allowed)
				(footprints allowed)
			)
			(placement
				(enabled no)
				(sheetname "")
			)
			(fill
				(thermal_gap 0.5)
				(thermal_bridge_width 0.5)
				(island_removal_mode 0)
			)
			(polygon
				(pts
					(xy 114.9858 -82.7532) (xy 115.1382 -82.7532) (xy 115.1382 -83.3628) (xy 114.9858 -83.3628)
				)
			)
		)
		(zone
			(layer "F.Cu")
			(hatch none 0.5)
			(connect_pads
				(clearance 0)
			)
			(min_thickness 0.25)
			(keepout
				(tracks not_allowed)
				(vias allowed)
				(pads allowed)
				(copperpour not_allowed)
				(footprints allowed)
			)
			(placement
				(enabled no)
				(sheetname "")
			)
			(fill
				(thermal_gap 0.5)
				(thermal_bridge_width 0.5)
				(island_removal_mode 0)
			)
			(polygon
				(pts
					(xy 114.9858 -82.7532) (xy 115.1382 -82.7532) (xy 115.1382 -83.3628) (xy 114.9858 -83.3628)
				)
			)
		)
	)
)
